(kicad_pcb
	(version 20260206)
	(generator "pcbnew")
	(generator_version "10.0")
	(general
		(thickness 1.6)
		(legacy_teardrops no)
	)
	(paper "A4")
	(title_block
		(title "01162023_DA0F0TEBIF0_F0T_Expander_BD_F_brd_V02_OCP.brd")
		(comment 1 "Grand Teton / footprints 4724-4730 of 9728")
	)
	(layers
		(0 "F.Cu" signal "TOP")
		(4 "In1.Cu" signal "GND")
		(6 "In2.Cu" signal "VCC")
		(8 "In3.Cu" signal "VCC1")
		(10 "In4.Cu" signal "GND1")
		(12 "In5.Cu" signal "IN1")
		(14 "In6.Cu" signal "GND2")
		(16 "In7.Cu" signal "IN2")
		(18 "In8.Cu" signal "GND3")
		(20 "In9.Cu" signal "IN3")
		(22 "In10.Cu" signal "GND4")
		(24 "In11.Cu" signal "IN4")
		(26 "In12.Cu" signal "GND5")
		(28 "In13.Cu" signal "IN5")
		(30 "In14.Cu" signal "GND6")
		(32 "In15.Cu" signal "IN6")
		(34 "In16.Cu" signal "GND7")
		(2 "B.Cu" signal "BOTTOM")
		(9 "F.Adhes" user "F.Adhesive")
		(11 "B.Adhes" user "B.Adhesive")
		(13 "F.Paste" user "Package Geometry/Pastemask Top")
		(15 "B.Paste" user "Package Geometry/Pastemask Bottom")
		(5 "F.SilkS" user "Ref Des/Silkscreen Top")
		(7 "B.SilkS" user "Ref Des/Silkscreen Bottom")
		(1 "F.Mask" user "Board Geometry/Soldermask Top")
		(3 "B.Mask" user "Board Geometry/Soldermask Bottom")
		(17 "Dwgs.User" user "User.Drawings")
		(19 "Cmts.User" user "User.Comments")
		(21 "Eco1.User" user "User.Eco1")
		(23 "Eco2.User" user "User.Eco2")
		(25 "Edge.Cuts" user "Board Geometry/Outline")
		(27 "Margin" user)
		(31 "F.CrtYd" user "Package Geometry/Place Bound Top")
		(29 "B.CrtYd" user "Package Geometry/Place Bound Bottom")
		(35 "F.Fab" user "Ref Des/Assembly Top")
		(33 "B.Fab" user "Ref Des/Assembly Bottom")
	)
	(footprint ""
		(layer "F.Cu")
		(at 408.529282 -202.362308 -90)
		(property "Reference" "R6441"
			(at 0 0 270)
			(layer "F.SilkS")
			(hide yes)
			(effects
				(font
					(size 1.27 1.27)
				)
			)
		)
		(property "Value" ""
			(at 0 0 270)
			(layer "F.Fab")
			(effects
				(font
					(size 1.27 1.27)
				)
			)
		)
		(duplicate_pad_numbers_are_jumpers no)
		(fp_line
			(start -0.7874 0.4064)
			(end -0.7874 -0.4064)
			(stroke
				(width 0.1524)
				(type default)
			)
			(layer "F.SilkS")
		)
		(fp_line
			(start 0.7874 0.4064)
			(end -0.7874 0.4064)
			(stroke
				(width 0.1524)
				(type default)
			)
			(layer "F.SilkS")
		)
		(fp_line
			(start -0.7874 -0.4064)
			(end 0.7874 -0.4064)
			(stroke
				(width 0.1524)
				(type default)
			)
			(layer "F.SilkS")
		)
		(fp_line
			(start 0.7874 -0.4064)
			(end 0.7874 0.4064)
			(stroke
				(width 0.1524)
				(type default)
			)
			(layer "F.SilkS")
		)
		(fp_line
			(start -0.67945 0.3048)
			(end -0.67945 -0.305054)
			(stroke
				(width 0.1)
				(type default)
			)
			(layer "F.Fab")
		)
		(fp_line
			(start -0.12065 0.3048)
			(end -0.67945 0.3048)
			(stroke
				(width 0.1)
				(type default)
			)
			(layer "F.Fab")
		)
		(fp_line
			(start 0.120396 0.3048)
			(end 0.120396 0.2794)
			(stroke
				(width 0.1)
				(type default)
			)
			(layer "F.Fab")
		)
		(fp_line
			(start 0.67945 0.3048)
			(end 0.120396 0.3048)
			(stroke
				(width 0.1)
				(type default)
			)
			(layer "F.Fab")
		)
		(fp_line
			(start -0.12065 0.2794)
			(end -0.12065 0.3048)
			(stroke
				(width 0.1)
				(type default)
			)
			(layer "F.Fab")
		)
		(fp_line
			(start 0.120396 0.2794)
			(end -0.12065 0.2794)
			(stroke
				(width 0.1)
				(type default)
			)
			(layer "F.Fab")
		)
		(fp_line
			(start -0.12065 -0.2794)
			(end 0.12065 -0.2794)
			(stroke
				(width 0.1)
				(type default)
			)
			(layer "F.Fab")
		)
		(fp_line
			(start 0.12065 -0.2794)
			(end 0.12065 -0.3048)
			(stroke
				(width 0.1)
				(type default)
			)
			(layer "F.Fab")
		)
		(fp_line
			(start 0.12065 -0.3048)
			(end 0.67945 -0.3048)
			(stroke
				(width 0.1)
				(type default)
			)
			(layer "F.Fab")
		)
		(fp_line
			(start 0.67945 -0.3048)
			(end 0.67945 0.3048)
			(stroke
				(width 0.1)
				(type default)
			)
			(layer "F.Fab")
		)
		(fp_line
			(start -0.67945 -0.305054)
			(end -0.12065 -0.305054)
			(stroke
				(width 0.1)
				(type default)
			)
			(layer "F.Fab")
		)
		(fp_line
			(start -0.12065 -0.305054)
			(end -0.12065 -0.2794)
			(stroke
				(width 0.1)
				(type default)
			)
			(layer "F.Fab")
		)
		(pad "1" smd circle
			(at -0.40005 0 270)
			(size 0 0)
			(layers "F.Cu" "F.Mask" "F.Paste")
			(net "FPGA_PEX2_MODE_SEL2_ISO")
		)
		(pad "2" smd circle
			(at 0.40005 0 270)
			(size 0 0)
			(layers "F.Cu" "F.Mask" "F.Paste")
			(net "PEX2_MODE_SEL2")
		)
	)
	(footprint ""
		(layer "F.Cu")
		(at 34.502344 -250.070874 -90)
		(property "Reference" "R1165"
			(at 0 0 270)
			(layer "F.SilkS")
			(hide yes)
			(effects
				(font
					(size 1.27 1.27)
				)
			)
		)
		(property "Value" ""
			(at 0 0 270)
			(layer "F.Fab")
			(effects
				(font
					(size 1.27 1.27)
				)
			)
		)
		(duplicate_pad_numbers_are_jumpers no)
		(fp_line
			(start -0.7874 0.4064)
			(end -0.7874 -0.4064)
			(stroke
				(width 0.1524)
				(type default)
			)
			(layer "F.SilkS")
		)
		(fp_line
			(start 0.7874 0.4064)
			(end -0.7874 0.4064)
			(stroke
				(width 0.1524)
				(type default)
			)
			(layer "F.SilkS")
		)
		(fp_line
			(start -0.7874 -0.4064)
			(end 0.7874 -0.4064)
			(stroke
				(width 0.1524)
				(type default)
			)
			(layer "F.SilkS")
		)
		(fp_line
			(start 0.7874 -0.4064)
			(end 0.7874 0.4064)
			(stroke
				(width 0.1524)
				(type default)
			)
			(layer "F.SilkS")
		)
		(fp_line
			(start -0.67945 0.3048)
			(end -0.67945 -0.305054)
			(stroke
				(width 0.1)
				(type default)
			)
			(layer "F.Fab")
		)
		(fp_line
			(start -0.12065 0.3048)
			(end -0.67945 0.3048)
			(stroke
				(width 0.1)
				(type default)
			)
			(layer "F.Fab")
		)
		(fp_line
			(start 0.120396 0.3048)
			(end 0.120396 0.2794)
			(stroke
				(width 0.1)
				(type default)
			)
			(layer "F.Fab")
		)
		(fp_line
			(start 0.67945 0.3048)
			(end 0.120396 0.3048)
			(stroke
				(width 0.1)
				(type default)
			)
			(layer "F.Fab")
		)
		(fp_line
			(start -0.12065 0.2794)
			(end -0.12065 0.3048)
			(stroke
				(width 0.1)
				(type default)
			)
			(layer "F.Fab")
		)
		(fp_line
			(start 0.120396 0.2794)
			(end -0.12065 0.2794)
			(stroke
				(width 0.1)
				(type default)
			)
			(layer "F.Fab")
		)
		(fp_line
			(start -0.12065 -0.2794)
			(end 0.12065 -0.2794)
			(stroke
				(width 0.1)
				(type default)
			)
			(layer "F.Fab")
		)
		(fp_line
			(start 0.12065 -0.2794)
			(end 0.12065 -0.3048)
			(stroke
				(width 0.1)
				(type default)
			)
			(layer "F.Fab")
		)
		(fp_line
			(start 0.12065 -0.3048)
			(end 0.67945 -0.3048)
			(stroke
				(width 0.1)
				(type default)
			)
			(layer "F.Fab")
		)
		(fp_line
			(start 0.67945 -0.3048)
			(end 0.67945 0.3048)
			(stroke
				(width 0.1)
				(type default)
			)
			(layer "F.Fab")
		)
		(fp_line
			(start -0.67945 -0.305054)
			(end -0.12065 -0.305054)
			(stroke
				(width 0.1)
				(type default)
			)
			(layer "F.Fab")
		)
		(fp_line
			(start -0.12065 -0.305054)
			(end -0.12065 -0.2794)
			(stroke
				(width 0.1)
				(type default)
			)
			(layer "F.Fab")
		)
		(pad "1" smd circle
			(at -0.40005 0 270)
			(size 0 0)
			(layers "F.Cu" "F.Mask" "F.Paste")
			(net "PEX0_MODE_SEL11")
		)
		(pad "2" smd circle
			(at 0.40005 0 270)
			(size 0 0)
			(layers "F.Cu" "F.Mask" "F.Paste")
			(net "P1V8_PEX")
		)
	)
	(footprint ""
		(layer "F.Cu")
		(at 431.20183 -32.849312 90)
		(property "Reference" "R5706"
			(at 0 0 90)
			(layer "F.SilkS")
			(hide yes)
			(effects
				(font
					(size 1.27 1.27)
				)
			)
		)
		(property "Value" ""
			(at 0 0 90)
			(layer "F.Fab")
			(effects
				(font
					(size 1.27 1.27)
				)
			)
		)
		(duplicate_pad_numbers_are_jumpers no)
		(fp_line
			(start 0.7874 -0.4064)
			(end 0.7874 0.4064)
			(stroke
				(width 0.1524)
				(type default)
			)
			(layer "F.SilkS")
		)
		(fp_line
			(start -0.7874 -0.4064)
			(end 0.7874 -0.4064)
			(stroke
				(width 0.1524)
				(type default)
			)
			(layer "F.SilkS")
		)
		(fp_line
			(start 0.7874 0.4064)
			(end -0.7874 0.4064)
			(stroke
				(width 0.1524)
				(type default)
			)
			(layer "F.SilkS")
		)
		(fp_line
			(start -0.7874 0.4064)
			(end -0.7874 -0.4064)
			(stroke
				(width 0.1524)
				(type default)
			)
			(layer "F.SilkS")
		)
		(fp_line
			(start -0.12065 -0.305054)
			(end -0.12065 -0.2794)
			(stroke
				(width 0.1)
				(type default)
			)
			(layer "F.Fab")
		)
		(fp_line
			(start -0.67945 -0.305054)
			(end -0.12065 -0.305054)
			(stroke
				(width 0.1)
				(type default)
			)
			(layer "F.Fab")
		)
		(fp_line
			(start 0.67945 -0.3048)
			(end 0.67945 0.3048)
			(stroke
				(width 0.1)
				(type default)
			)
			(layer "F.Fab")
		)
		(fp_line
			(start 0.12065 -0.3048)
			(end 0.67945 -0.3048)
			(stroke
				(width 0.1)
				(type default)
			)
			(layer "F.Fab")
		)
		(fp_line
			(start 0.12065 -0.2794)
			(end 0.12065 -0.3048)
			(stroke
				(width 0.1)
				(type default)
			)
			(layer "F.Fab")
		)
		(fp_line
			(start -0.12065 -0.2794)
			(end 0.12065 -0.2794)
			(stroke
				(width 0.1)
				(type default)
			)
			(layer "F.Fab")
		)
		(fp_line
			(start 0.120396 0.2794)
			(end -0.12065 0.2794)
			(stroke
				(width 0.1)
				(type default)
			)
			(layer "F.Fab")
		)
		(fp_line
			(start -0.12065 0.2794)
			(end -0.12065 0.3048)
			(stroke
				(width 0.1)
				(type default)
			)
			(layer "F.Fab")
		)
		(fp_line
			(start 0.67945 0.3048)
			(end 0.120396 0.3048)
			(stroke
				(width 0.1)
				(type default)
			)
			(layer "F.Fab")
		)
		(fp_line
			(start 0.120396 0.3048)
			(end 0.120396 0.2794)
			(stroke
				(width 0.1)
				(type default)
			)
			(layer "F.Fab")
		)
		(fp_line
			(start -0.12065 0.3048)
			(end -0.67945 0.3048)
			(stroke
				(width 0.1)
				(type default)
			)
			(layer "F.Fab")
		)
		(fp_line
			(start -0.67945 0.3048)
			(end -0.67945 -0.305054)
			(stroke
				(width 0.1)
				(type default)
			)
			(layer "F.Fab")
		)
		(pad "1" smd circle
			(at -0.40005 0 90)
			(size 0 0)
			(layers "F.Cu" "F.Mask" "F.Paste")
			(net "RST_SMB_SSD15_ISO_R_N")
		)
		(pad "2" smd circle
			(at 0.40005 0 90)
			(size 0 0)
			(layers "F.Cu" "F.Mask" "F.Paste")
			(net "RST_SMB_SSD15_ISO_N")
		)
	)
	(footprint ""
		(layer "F.Cu")
		(at 246.554498 -135.993632 -90)
		(property "Reference" "PC309"
			(at 0 0 270)
			(layer "F.SilkS")
			(hide yes)
			(effects
				(font
					(size 1.27 1.27)
				)
			)
		)
		(property "Value" ""
			(at 0 0 270)
			(layer "F.Fab")
			(effects
				(font
					(size 1.27 1.27)
				)
			)
		)
		(duplicate_pad_numbers_are_jumpers no)
		(fp_line
			(start -0.7874 0.4064)
			(end -0.7874 -0.4064)
			(stroke
				(width 0.1524)
				(type default)
			)
			(layer "F.SilkS")
		)
		(fp_line
			(start 0.7874 0.4064)
			(end -0.7874 0.4064)
			(stroke
				(width 0.1524)
				(type default)
			)
			(layer "F.SilkS")
		)
		(fp_line
			(start -0.7874 -0.4064)
			(end 0.7874 -0.4064)
			(stroke
				(width 0.1524)
				(type default)
			)
			(layer "F.SilkS")
		)
		(fp_line
			(start 0.7874 -0.4064)
			(end 0.7874 0.4064)
			(stroke
				(width 0.1524)
				(type default)
			)
			(layer "F.SilkS")
		)
		(fp_line
			(start -0.67945 0.3048)
			(end -0.67945 -0.305054)
			(stroke
				(width 0.1)
				(type default)
			)
			(layer "F.Fab")
		)
		(fp_line
			(start -0.12065 0.3048)
			(end -0.67945 0.3048)
			(stroke
				(width 0.1)
				(type default)
			)
			(layer "F.Fab")
		)
		(fp_line
			(start 0.120396 0.3048)
			(end 0.120396 0.2794)
			(stroke
				(width 0.1)
				(type default)
			)
			(layer "F.Fab")
		)
		(fp_line
			(start 0.67945 0.3048)
			(end 0.120396 0.3048)
			(stroke
				(width 0.1)
				(type default)
			)
			(layer "F.Fab")
		)
		(fp_line
			(start -0.12065 0.2794)
			(end -0.12065 0.3048)
			(stroke
				(width 0.1)
				(type default)
			)
			(layer "F.Fab")
		)
		(fp_line
			(start 0.120396 0.2794)
			(end -0.12065 0.2794)
			(stroke
				(width 0.1)
				(type default)
			)
			(layer "F.Fab")
		)
		(fp_line
			(start -0.12065 -0.2794)
			(end 0.12065 -0.2794)
			(stroke
				(width 0.1)
				(type default)
			)
			(layer "F.Fab")
		)
		(fp_line
			(start 0.12065 -0.2794)
			(end 0.12065 -0.3048)
			(stroke
				(width 0.1)
				(type default)
			)
			(layer "F.Fab")
		)
		(fp_line
			(start 0.12065 -0.3048)
			(end 0.67945 -0.3048)
			(stroke
				(width 0.1)
				(type default)
			)
			(layer "F.Fab")
		)
		(fp_line
			(start 0.67945 -0.3048)
			(end 0.67945 0.3048)
			(stroke
				(width 0.1)
				(type default)
			)
			(layer "F.Fab")
		)
		(fp_line
			(start -0.67945 -0.305054)
			(end -0.12065 -0.305054)
			(stroke
				(width 0.1)
				(type default)
			)
			(layer "F.Fab")
		)
		(fp_line
			(start -0.12065 -0.305054)
			(end -0.12065 -0.2794)
			(stroke
				(width 0.1)
				(type default)
			)
			(layer "F.Fab")
		)
		(pad "1" smd circle
			(at -0.40005 0 270)
			(size 0 0)
			(layers "F.Cu" "F.Mask" "F.Paste")
			(net "P12V_NIC4_R")
		)
		(pad "2" smd circle
			(at 0.40005 0 270)
			(size 0 0)
			(layers "F.Cu" "F.Mask" "F.Paste")
			(net "GND")
		)
	)
	(footprint ""
		(layer "F.Cu")
		(at 134.513828 -356.244906 90)
		(property "Reference" "C2268"
			(at 0 0 90)
			(layer "F.SilkS")
			(hide yes)
			(effects
				(font
					(size 1.27 1.27)
				)
			)
		)
		(property "Value" ""
			(at 0 0 90)
			(layer "F.Fab")
			(effects
				(font
					(size 1.27 1.27)
				)
			)
		)
		(duplicate_pad_numbers_are_jumpers no)
		(fp_line
			(start 0.299974 -0.150114)
			(end 0.299974 0.150114)
			(stroke
				(width 0.1)
				(type default)
			)
			(layer "F.Fab")
		)
		(fp_line
			(start -0.299974 -0.150114)
			(end 0.299974 -0.150114)
			(stroke
				(width 0.1)
				(type default)
			)
			(layer "F.Fab")
		)
		(fp_line
			(start 0.299974 0.150114)
			(end -0.299974 0.150114)
			(stroke
				(width 0.1)
				(type default)
			)
			(layer "F.Fab")
		)
		(fp_line
			(start -0.299974 0.150114)
			(end -0.299974 -0.150114)
			(stroke
				(width 0.1)
				(type default)
			)
			(layer "F.Fab")
		)
		(pad "1" smd rect
			(at -0.2667 0 90)
			(size 0.3048 0.381)
			(layers "F.Cu" "F.Mask" "F.Paste")
			(net "P5E_PEX1_STN5_TX_DN<83>")
		)
		(pad "2" smd rect
			(at 0.2667 0 90)
			(size 0.3048 0.381)
			(layers "F.Cu" "F.Mask" "F.Paste")
			(net "P5E_PEX1_STN5_TX_C_DN<83>")
		)
	)
	(footprint ""
		(layer "F.Cu")
		(at 117.958362 -126.915926)
		(property "Reference" "R4440"
			(at 0 0 0)
			(layer "F.SilkS")
			(hide yes)
			(effects
				(font
					(size 1.27 1.27)
				)
			)
		)
		(property "Value" ""
			(at 0 0 0)
			(layer "F.Fab")
			(effects
				(font
					(size 1.27 1.27)
				)
			)
		)
		(duplicate_pad_numbers_are_jumpers no)
		(fp_line
			(start -0.7874 -0.4064)
			(end 0.7874 -0.4064)
			(stroke
				(width 0.1524)
				(type default)
			)
			(layer "F.SilkS")
		)
		(fp_line
			(start -0.7874 0.4064)
			(end -0.7874 -0.4064)
			(stroke
				(width 0.1524)
				(type default)
			)
			(layer "F.SilkS")
		)
		(fp_line
			(start 0.7874 -0.4064)
			(end 0.7874 0.4064)
			(stroke
				(width 0.1524)
				(type default)
			)
			(layer "F.SilkS")
		)
		(fp_line
			(start 0.7874 0.4064)
			(end -0.7874 0.4064)
			(stroke
				(width 0.1524)
				(type default)
			)
			(layer "F.SilkS")
		)
		(fp_line
			(start -0.67945 -0.305054)
			(end -0.12065 -0.305054)
			(stroke
				(width 0.1)
				(type default)
			)
			(layer "F.Fab")
		)
		(fp_line
			(start -0.67945 0.3048)
			(end -0.67945 -0.305054)
			(stroke
				(width 0.1)
				(type default)
			)
			(layer "F.Fab")
		)
		(fp_line
			(start -0.12065 -0.305054)
			(end -0.12065 -0.2794)
			(stroke
				(width 0.1)
				(type default)
			)
			(layer "F.Fab")
		)
		(fp_line
			(start -0.12065 -0.2794)
			(end 0.12065 -0.2794)
			(stroke
				(width 0.1)
				(type default)
			)
			(layer "F.Fab")
		)
		(fp_line
			(start -0.12065 0.2794)
			(end -0.12065 0.3048)
			(stroke
				(width 0.1)
				(type default)
			)
			(layer "F.Fab")
		)
		(fp_line
			(start -0.12065 0.3048)
			(end -0.67945 0.3048)
			(stroke
				(width 0.1)
				(type default)
			)
			(layer "F.Fab")
		)
		(fp_line
			(start 0.120396 0.2794)
			(end -0.12065 0.2794)
			(stroke
				(width 0.1)
				(type default)
			)
			(layer "F.Fab")
		)
		(fp_line
			(start 0.120396 0.3048)
			(end 0.120396 0.2794)
			(stroke
				(width 0.1)
				(type default)
			)
			(layer "F.Fab")
		)
		(fp_line
			(start 0.12065 -0.3048)
			(end 0.67945 -0.3048)
			(stroke
				(width 0.1)
				(type default)
			)
			(layer "F.Fab")
		)
		(fp_line
			(start 0.12065 -0.2794)
			(end 0.12065 -0.3048)
			(stroke
				(width 0.1)
				(type default)
			)
			(layer "F.Fab")
		)
		(fp_line
			(start 0.67945 -0.3048)
			(end 0.67945 0.3048)
			(stroke
				(width 0.1)
				(type default)
			)
			(layer "F.Fab")
		)
		(fp_line
			(start 0.67945 0.3048)
			(end 0.120396 0.3048)
			(stroke
				(width 0.1)
				(type default)
			)
			(layer "F.Fab")
		)
		(pad "1" smd circle
			(at -0.40005 0)
			(size 0 0)
			(layers "F.Cu" "F.Mask" "F.Paste")
			(net "PWRGD_P3V3")
		)
		(pad "2" smd circle
			(at 0.40005 0)
			(size 0 0)
			(layers "F.Cu" "F.Mask" "F.Paste")
			(net "PWRGD_P3V3_R")
		)
	)
	(footprint ""
		(layer "F.Cu")
		(at 90.867992 -289.230816 90)
		(property "Reference" "R3879"
			(at 0 0 90)
			(layer "F.SilkS")
			(hide yes)
			(effects
				(font
					(size 1.27 1.27)
				)
			)
		)
		(property "Value" ""
			(at 0 0 90)
			(layer "F.Fab")
			(effects
				(font
					(size 1.27 1.27)
				)
			)
		)
		(duplicate_pad_numbers_are_jumpers no)
		(fp_line
			(start 0.7874 -0.4064)
			(end 0.7874 0.4064)
			(stroke
				(width 0.1524)
				(type default)
			)
			(layer "F.SilkS")
		)
		(fp_line
			(start -0.7874 -0.4064)
			(end 0.7874 -0.4064)
			(stroke
				(width 0.1524)
				(type default)
			)
			(layer "F.SilkS")
		)
		(fp_line
			(start 0.7874 0.4064)
			(end -0.7874 0.4064)
			(stroke
				(width 0.1524)
				(type default)
			)
			(layer "F.SilkS")
		)
		(fp_line
			(start -0.7874 0.4064)
			(end -0.7874 -0.4064)
			(stroke
				(width 0.1524)
				(type default)
			)
			(layer "F.SilkS")
		)
		(fp_line
			(start -0.12065 -0.305054)
			(end -0.12065 -0.2794)
			(stroke
				(width 0.1)
				(type default)
			)
			(layer "F.Fab")
		)
		(fp_line
			(start -0.67945 -0.305054)
			(end -0.12065 -0.305054)
			(stroke
				(width 0.1)
				(type default)
			)
			(layer "F.Fab")
		)
		(fp_line
			(start 0.67945 -0.3048)
			(end 0.67945 0.3048)
			(stroke
				(width 0.1)
				(type default)
			)
			(layer "F.Fab")
		)
		(fp_line
			(start 0.12065 -0.3048)
			(end 0.67945 -0.3048)
			(stroke
				(width 0.1)
				(type default)
			)
			(layer "F.Fab")
		)
		(fp_line
			(start 0.12065 -0.2794)
			(end 0.12065 -0.3048)
			(stroke
				(width 0.1)
				(type default)
			)
			(layer "F.Fab")
		)
		(fp_line
			(start -0.12065 -0.2794)
			(end 0.12065 -0.2794)
			(stroke
				(width 0.1)
				(type default)
			)
			(layer "F.Fab")
		)
		(fp_line
			(start 0.120396 0.2794)
			(end -0.12065 0.2794)
			(stroke
				(width 0.1)
				(type default)
			)
			(layer "F.Fab")
		)
		(fp_line
			(start -0.12065 0.2794)
			(end -0.12065 0.3048)
			(stroke
				(width 0.1)
				(type default)
			)
			(layer "F.Fab")
		)
		(fp_line
			(start 0.67945 0.3048)
			(end 0.120396 0.3048)
			(stroke
				(width 0.1)
				(type default)
			)
			(layer "F.Fab")
		)
		(fp_line
			(start 0.120396 0.3048)
			(end 0.120396 0.2794)
			(stroke
				(width 0.1)
				(type default)
			)
			(layer "F.Fab")
		)
		(fp_line
			(start -0.12065 0.3048)
			(end -0.67945 0.3048)
			(stroke
				(width 0.1)
				(type default)
			)
			(layer "F.Fab")
		)
		(fp_line
			(start -0.67945 0.3048)
			(end -0.67945 -0.305054)
			(stroke
				(width 0.1)
				(type default)
			)
			(layer "F.Fab")
		)
		(pad "1" smd circle
			(at -0.40005 0 90)
			(size 0 0)
			(layers "F.Cu" "F.Mask" "F.Paste")
			(net "SMB_PEX0_PCA9555_SCL")
		)
		(pad "2" smd circle
			(at 0.40005 0 90)
			(size 0 0)
			(layers "F.Cu" "F.Mask" "F.Paste")
			(net "SMB_PEX0_HOST_LS_SCL")
		)
	)
)
